(kicad_pcb
	(version 20260206)
	(generator "pcbnew")
	(generator_version "10.0")
	(general
		(thickness 1.6)
		(legacy_teardrops no)
	)
	(paper "A4")
	(title_block
		(title "01162023_DA0F0TEBIF0_F0T_Expander_BD_F_brd_V02_OCP.brd")
		(comment 1 "Grand Teton / footprints 1205-1211 of 9728")
	)
	(layers
		(0 "F.Cu" signal "TOP")
		(4 "In1.Cu" signal "GND")
		(6 "In2.Cu" signal "VCC")
		(8 "In3.Cu" signal "VCC1")
		(10 "In4.Cu" signal "GND1")
		(12 "In5.Cu" signal "IN1")
		(14 "In6.Cu" signal "GND2")
		(16 "In7.Cu" signal "IN2")
		(18 "In8.Cu" signal "GND3")
		(20 "In9.Cu" signal "IN3")
		(22 "In10.Cu" signal "GND4")
		(24 "In11.Cu" signal "IN4")
		(26 "In12.Cu" signal "GND5")
		(28 "In13.Cu" signal "IN5")
		(30 "In14.Cu" signal "GND6")
		(32 "In15.Cu" signal "IN6")
		(34 "In16.Cu" signal "GND7")
		(2 "B.Cu" signal "BOTTOM")
		(9 "F.Adhes" user "F.Adhesive")
		(11 "B.Adhes" user "B.Adhesive")
		(13 "F.Paste" user "Package Geometry/Pastemask Top")
		(15 "B.Paste" user "Package Geometry/Pastemask Bottom")
		(5 "F.SilkS" user "Ref Des/Silkscreen Top")
		(7 "B.SilkS" user "Ref Des/Silkscreen Bottom")
		(1 "F.Mask" user "Board Geometry/Soldermask Top")
		(3 "B.Mask" user "Board Geometry/Soldermask Bottom")
		(17 "Dwgs.User" user "User.Drawings")
		(19 "Cmts.User" user "User.Comments")
		(21 "Eco1.User" user "User.Eco1")
		(23 "Eco2.User" user "User.Eco2")
		(25 "Edge.Cuts" user "Board Geometry/Outline")
		(27 "Margin" user)
		(31 "F.CrtYd" user "Package Geometry/Place Bound Top")
		(29 "B.CrtYd" user "Package Geometry/Place Bound Bottom")
		(35 "F.Fab" user "Ref Des/Assembly Top")
		(33 "B.Fab" user "Ref Des/Assembly Bottom")
	)
	(footprint ""
		(layer "F.Cu")
		(at 404.12924 -116.5352 180)
		(property "Reference" "R346"
			(at 0 0 180)
			(layer "F.SilkS")
			(hide yes)
			(effects
				(font
					(size 1.27 1.27)
				)
			)
		)
		(property "Value" ""
			(at 0 0 180)
			(layer "F.Fab")
			(effects
				(font
					(size 1.27 1.27)
				)
			)
		)
		(duplicate_pad_numbers_are_jumpers no)
		(fp_line
			(start 0.7874 0.4064)
			(end -0.7874 0.4064)
			(stroke
				(width 0.1524)
				(type default)
			)
			(layer "F.SilkS")
		)
		(fp_line
			(start 0.7874 -0.4064)
			(end 0.7874 0.4064)
			(stroke
				(width 0.1524)
				(type default)
			)
			(layer "F.SilkS")
		)
		(fp_line
			(start -0.7874 0.4064)
			(end -0.7874 -0.4064)
			(stroke
				(width 0.1524)
				(type default)
			)
			(layer "F.SilkS")
		)
		(fp_line
			(start -0.7874 -0.4064)
			(end 0.7874 -0.4064)
			(stroke
				(width 0.1524)
				(type default)
			)
			(layer "F.SilkS")
		)
		(fp_line
			(start 0.67945 0.3048)
			(end 0.120396 0.3048)
			(stroke
				(width 0.1)
				(type default)
			)
			(layer "F.Fab")
		)
		(fp_line
			(start 0.67945 -0.3048)
			(end 0.67945 0.3048)
			(stroke
				(width 0.1)
				(type default)
			)
			(layer "F.Fab")
		)
		(fp_line
			(start 0.12065 -0.2794)
			(end 0.12065 -0.3048)
			(stroke
				(width 0.1)
				(type default)
			)
			(layer "F.Fab")
		)
		(fp_line
			(start 0.12065 -0.3048)
			(end 0.67945 -0.3048)
			(stroke
				(width 0.1)
				(type default)
			)
			(layer "F.Fab")
		)
		(fp_line
			(start 0.120396 0.3048)
			(end 0.120396 0.2794)
			(stroke
				(width 0.1)
				(type default)
			)
			(layer "F.Fab")
		)
		(fp_line
			(start 0.120396 0.2794)
			(end -0.12065 0.2794)
			(stroke
				(width 0.1)
				(type default)
			)
			(layer "F.Fab")
		)
		(fp_line
			(start -0.12065 0.3048)
			(end -0.67945 0.3048)
			(stroke
				(width 0.1)
				(type default)
			)
			(layer "F.Fab")
		)
		(fp_line
			(start -0.12065 0.2794)
			(end -0.12065 0.3048)
			(stroke
				(width 0.1)
				(type default)
			)
			(layer "F.Fab")
		)
		(fp_line
			(start -0.12065 -0.2794)
			(end 0.12065 -0.2794)
			(stroke
				(width 0.1)
				(type default)
			)
			(layer "F.Fab")
		)
		(fp_line
			(start -0.12065 -0.305054)
			(end -0.12065 -0.2794)
			(stroke
				(width 0.1)
				(type default)
			)
			(layer "F.Fab")
		)
		(fp_line
			(start -0.67945 0.3048)
			(end -0.67945 -0.305054)
			(stroke
				(width 0.1)
				(type default)
			)
			(layer "F.Fab")
		)
		(fp_line
			(start -0.67945 -0.305054)
			(end -0.12065 -0.305054)
			(stroke
				(width 0.1)
				(type default)
			)
			(layer "F.Fab")
		)
		(pad "1" smd circle
			(at -0.40005 0 180)
			(size 0 0)
			(layers "F.Cu" "F.Mask" "F.Paste")
			(net "PRSNT_NIC6_N")
		)
		(pad "2" smd circle
			(at 0.40005 0 180)
			(size 0 0)
			(layers "F.Cu" "F.Mask" "F.Paste")
			(net "PRSNTB1_NIC6_N")
		)
	)
	(footprint ""
		(layer "F.Cu")
		(at 101.930454 -121.80824 180)
		(property "Reference" "R5865"
			(at 0 0 180)
			(layer "F.SilkS")
			(hide yes)
			(effects
				(font
					(size 1.27 1.27)
				)
			)
		)
		(property "Value" ""
			(at 0 0 180)
			(layer "F.Fab")
			(effects
				(font
					(size 1.27 1.27)
				)
			)
		)
		(duplicate_pad_numbers_are_jumpers no)
		(fp_line
			(start 0.7874 0.4064)
			(end -0.7874 0.4064)
			(stroke
				(width 0.1524)
				(type default)
			)
			(layer "F.SilkS")
		)
		(fp_line
			(start 0.7874 -0.4064)
			(end 0.7874 0.4064)
			(stroke
				(width 0.1524)
				(type default)
			)
			(layer "F.SilkS")
		)
		(fp_line
			(start -0.7874 0.4064)
			(end -0.7874 -0.4064)
			(stroke
				(width 0.1524)
				(type default)
			)
			(layer "F.SilkS")
		)
		(fp_line
			(start -0.7874 -0.4064)
			(end 0.7874 -0.4064)
			(stroke
				(width 0.1524)
				(type default)
			)
			(layer "F.SilkS")
		)
		(fp_line
			(start 0.67945 0.3048)
			(end 0.120396 0.3048)
			(stroke
				(width 0.1)
				(type default)
			)
			(layer "F.Fab")
		)
		(fp_line
			(start 0.67945 -0.3048)
			(end 0.67945 0.3048)
			(stroke
				(width 0.1)
				(type default)
			)
			(layer "F.Fab")
		)
		(fp_line
			(start 0.12065 -0.2794)
			(end 0.12065 -0.3048)
			(stroke
				(width 0.1)
				(type default)
			)
			(layer "F.Fab")
		)
		(fp_line
			(start 0.12065 -0.3048)
			(end 0.67945 -0.3048)
			(stroke
				(width 0.1)
				(type default)
			)
			(layer "F.Fab")
		)
		(fp_line
			(start 0.120396 0.3048)
			(end 0.120396 0.2794)
			(stroke
				(width 0.1)
				(type default)
			)
			(layer "F.Fab")
		)
		(fp_line
			(start 0.120396 0.2794)
			(end -0.12065 0.2794)
			(stroke
				(width 0.1)
				(type default)
			)
			(layer "F.Fab")
		)
		(fp_line
			(start -0.12065 0.3048)
			(end -0.67945 0.3048)
			(stroke
				(width 0.1)
				(type default)
			)
			(layer "F.Fab")
		)
		(fp_line
			(start -0.12065 0.2794)
			(end -0.12065 0.3048)
			(stroke
				(width 0.1)
				(type default)
			)
			(layer "F.Fab")
		)
		(fp_line
			(start -0.12065 -0.2794)
			(end 0.12065 -0.2794)
			(stroke
				(width 0.1)
				(type default)
			)
			(layer "F.Fab")
		)
		(fp_line
			(start -0.12065 -0.305054)
			(end -0.12065 -0.2794)
			(stroke
				(width 0.1)
				(type default)
			)
			(layer "F.Fab")
		)
		(fp_line
			(start -0.67945 0.3048)
			(end -0.67945 -0.305054)
			(stroke
				(width 0.1)
				(type default)
			)
			(layer "F.Fab")
		)
		(fp_line
			(start -0.67945 -0.305054)
			(end -0.12065 -0.305054)
			(stroke
				(width 0.1)
				(type default)
			)
			(layer "F.Fab")
		)
		(pad "1" smd circle
			(at -0.40005 0 180)
			(size 0 0)
			(layers "F.Cu" "F.Mask" "F.Paste")
			(net "P3V3_NIC1_PG_G1")
		)
		(pad "2" smd circle
			(at 0.40005 0 180)
			(size 0 0)
			(layers "F.Cu" "F.Mask" "F.Paste")
			(net "GND")
		)
	)
	(footprint ""
		(layer "F.Cu")
		(at 200.809098 -27.04973 180)
		(property "Reference" "C2770"
			(at 0 0 180)
			(layer "F.SilkS")
			(hide yes)
			(effects
				(font
					(size 1.27 1.27)
				)
			)
		)
		(property "Value" ""
			(at 0 0 180)
			(layer "F.Fab")
			(effects
				(font
					(size 1.27 1.27)
				)
			)
		)
		(duplicate_pad_numbers_are_jumpers no)
		(fp_line
			(start 0.7874 0.4064)
			(end -0.7874 0.4064)
			(stroke
				(width 0.1524)
				(type default)
			)
			(layer "F.SilkS")
		)
		(fp_line
			(start 0.7874 -0.4064)
			(end 0.7874 0.4064)
			(stroke
				(width 0.1524)
				(type default)
			)
			(layer "F.SilkS")
		)
		(fp_line
			(start -0.7874 0.4064)
			(end -0.7874 -0.4064)
			(stroke
				(width 0.1524)
				(type default)
			)
			(layer "F.SilkS")
		)
		(fp_line
			(start -0.7874 -0.4064)
			(end 0.7874 -0.4064)
			(stroke
				(width 0.1524)
				(type default)
			)
			(layer "F.SilkS")
		)
		(fp_line
			(start 0.67945 0.3048)
			(end 0.120396 0.3048)
			(stroke
				(width 0.1)
				(type default)
			)
			(layer "F.Fab")
		)
		(fp_line
			(start 0.67945 -0.3048)
			(end 0.67945 0.3048)
			(stroke
				(width 0.1)
				(type default)
			)
			(layer "F.Fab")
		)
		(fp_line
			(start 0.12065 -0.2794)
			(end 0.12065 -0.3048)
			(stroke
				(width 0.1)
				(type default)
			)
			(layer "F.Fab")
		)
		(fp_line
			(start 0.12065 -0.3048)
			(end 0.67945 -0.3048)
			(stroke
				(width 0.1)
				(type default)
			)
			(layer "F.Fab")
		)
		(fp_line
			(start 0.120396 0.3048)
			(end 0.120396 0.2794)
			(stroke
				(width 0.1)
				(type default)
			)
			(layer "F.Fab")
		)
		(fp_line
			(start 0.120396 0.2794)
			(end -0.12065 0.2794)
			(stroke
				(width 0.1)
				(type default)
			)
			(layer "F.Fab")
		)
		(fp_line
			(start -0.12065 0.3048)
			(end -0.67945 0.3048)
			(stroke
				(width 0.1)
				(type default)
			)
			(layer "F.Fab")
		)
		(fp_line
			(start -0.12065 0.2794)
			(end -0.12065 0.3048)
			(stroke
				(width 0.1)
				(type default)
			)
			(layer "F.Fab")
		)
		(fp_line
			(start -0.12065 -0.2794)
			(end 0.12065 -0.2794)
			(stroke
				(width 0.1)
				(type default)
			)
			(layer "F.Fab")
		)
		(fp_line
			(start -0.12065 -0.305054)
			(end -0.12065 -0.2794)
			(stroke
				(width 0.1)
				(type default)
			)
			(layer "F.Fab")
		)
		(fp_line
			(start -0.67945 0.3048)
			(end -0.67945 -0.305054)
			(stroke
				(width 0.1)
				(type default)
			)
			(layer "F.Fab")
		)
		(fp_line
			(start -0.67945 -0.305054)
			(end -0.12065 -0.305054)
			(stroke
				(width 0.1)
				(type default)
			)
			(layer "F.Fab")
		)
		(pad "1" smd circle
			(at -0.40005 0 180)
			(size 0 0)
			(layers "F.Cu" "F.Mask" "F.Paste")
			(net "PRSNT_SSD7_R_N")
		)
		(pad "2" smd circle
			(at 0.40005 0 180)
			(size 0 0)
			(layers "F.Cu" "F.Mask" "F.Paste")
			(net "GND")
		)
	)
	(footprint ""
		(layer "F.Cu")
		(at 405.956262 -61.487812 180)
		(property "Reference" "R6022"
			(at 0 0 180)
			(layer "F.SilkS")
			(hide yes)
			(effects
				(font
					(size 1.27 1.27)
				)
			)
		)
		(property "Value" ""
			(at 0 0 180)
			(layer "F.Fab")
			(effects
				(font
					(size 1.27 1.27)
				)
			)
		)
		(duplicate_pad_numbers_are_jumpers no)
		(fp_line
			(start 0.7874 0.4064)
			(end -0.7874 0.4064)
			(stroke
				(width 0.1524)
				(type default)
			)
			(layer "F.SilkS")
		)
		(fp_line
			(start 0.7874 -0.4064)
			(end 0.7874 0.4064)
			(stroke
				(width 0.1524)
				(type default)
			)
			(layer "F.SilkS")
		)
		(fp_line
			(start -0.7874 0.4064)
			(end -0.7874 -0.4064)
			(stroke
				(width 0.1524)
				(type default)
			)
			(layer "F.SilkS")
		)
		(fp_line
			(start -0.7874 -0.4064)
			(end 0.7874 -0.4064)
			(stroke
				(width 0.1524)
				(type default)
			)
			(layer "F.SilkS")
		)
		(fp_line
			(start 0.67945 0.3048)
			(end 0.120396 0.3048)
			(stroke
				(width 0.1)
				(type default)
			)
			(layer "F.Fab")
		)
		(fp_line
			(start 0.67945 -0.3048)
			(end 0.67945 0.3048)
			(stroke
				(width 0.1)
				(type default)
			)
			(layer "F.Fab")
		)
		(fp_line
			(start 0.12065 -0.2794)
			(end 0.12065 -0.3048)
			(stroke
				(width 0.1)
				(type default)
			)
			(layer "F.Fab")
		)
		(fp_line
			(start 0.12065 -0.3048)
			(end 0.67945 -0.3048)
			(stroke
				(width 0.1)
				(type default)
			)
			(layer "F.Fab")
		)
		(fp_line
			(start 0.120396 0.3048)
			(end 0.120396 0.2794)
			(stroke
				(width 0.1)
				(type default)
			)
			(layer "F.Fab")
		)
		(fp_line
			(start 0.120396 0.2794)
			(end -0.12065 0.2794)
			(stroke
				(width 0.1)
				(type default)
			)
			(layer "F.Fab")
		)
		(fp_line
			(start -0.12065 0.3048)
			(end -0.67945 0.3048)
			(stroke
				(width 0.1)
				(type default)
			)
			(layer "F.Fab")
		)
		(fp_line
			(start -0.12065 0.2794)
			(end -0.12065 0.3048)
			(stroke
				(width 0.1)
				(type default)
			)
			(layer "F.Fab")
		)
		(fp_line
			(start -0.12065 -0.2794)
			(end 0.12065 -0.2794)
			(stroke
				(width 0.1)
				(type default)
			)
			(layer "F.Fab")
		)
		(fp_line
			(start -0.12065 -0.305054)
			(end -0.12065 -0.2794)
			(stroke
				(width 0.1)
				(type default)
			)
			(layer "F.Fab")
		)
		(fp_line
			(start -0.67945 0.3048)
			(end -0.67945 -0.305054)
			(stroke
				(width 0.1)
				(type default)
			)
			(layer "F.Fab")
		)
		(fp_line
			(start -0.67945 -0.305054)
			(end -0.12065 -0.305054)
			(stroke
				(width 0.1)
				(type default)
			)
			(layer "F.Fab")
		)
		(pad "1" smd circle
			(at -0.40005 0 180)
			(size 0 0)
			(layers "F.Cu" "F.Mask" "F.Paste")
			(net "P3V3_AUX")
		)
		(pad "2" smd circle
			(at 0.40005 0 180)
			(size 0 0)
			(layers "F.Cu" "F.Mask" "F.Paste")
			(net "PWRGD_P12V_SSD14_D")
		)
	)
	(footprint ""
		(layer "F.Cu")
		(at 370.361972 -241.54892 180)
		(property "Reference" "C4189"
			(at 0 0 180)
			(layer "F.SilkS")
			(hide yes)
			(effects
				(font
					(size 1.27 1.27)
				)
			)
		)
		(property "Value" ""
			(at 0 0 180)
			(layer "F.Fab")
			(effects
				(font
					(size 1.27 1.27)
				)
			)
		)
		(duplicate_pad_numbers_are_jumpers no)
		(fp_line
			(start 0.7874 0.4064)
			(end -0.7874 0.4064)
			(stroke
				(width 0.1524)
				(type default)
			)
			(layer "F.SilkS")
		)
		(fp_line
			(start 0.7874 -0.4064)
			(end 0.7874 0.4064)
			(stroke
				(width 0.1524)
				(type default)
			)
			(layer "F.SilkS")
		)
		(fp_line
			(start -0.7874 0.4064)
			(end -0.7874 -0.4064)
			(stroke
				(width 0.1524)
				(type default)
			)
			(layer "F.SilkS")
		)
		(fp_line
			(start -0.7874 -0.4064)
			(end 0.7874 -0.4064)
			(stroke
				(width 0.1524)
				(type default)
			)
			(layer "F.SilkS")
		)
		(fp_line
			(start 0.67945 0.3048)
			(end 0.120396 0.3048)
			(stroke
				(width 0.1)
				(type default)
			)
			(layer "F.Fab")
		)
		(fp_line
			(start 0.67945 -0.3048)
			(end 0.67945 0.3048)
			(stroke
				(width 0.1)
				(type default)
			)
			(layer "F.Fab")
		)
		(fp_line
			(start 0.12065 -0.2794)
			(end 0.12065 -0.3048)
			(stroke
				(width 0.1)
				(type default)
			)
			(layer "F.Fab")
		)
		(fp_line
			(start 0.12065 -0.3048)
			(end 0.67945 -0.3048)
			(stroke
				(width 0.1)
				(type default)
			)
			(layer "F.Fab")
		)
		(fp_line
			(start 0.120396 0.3048)
			(end 0.120396 0.2794)
			(stroke
				(width 0.1)
				(type default)
			)
			(layer "F.Fab")
		)
		(fp_line
			(start 0.120396 0.2794)
			(end -0.12065 0.2794)
			(stroke
				(width 0.1)
				(type default)
			)
			(layer "F.Fab")
		)
		(fp_line
			(start -0.12065 0.3048)
			(end -0.67945 0.3048)
			(stroke
				(width 0.1)
				(type default)
			)
			(layer "F.Fab")
		)
		(fp_line
			(start -0.12065 0.2794)
			(end -0.12065 0.3048)
			(stroke
				(width 0.1)
				(type default)
			)
			(layer "F.Fab")
		)
		(fp_line
			(start -0.12065 -0.2794)
			(end 0.12065 -0.2794)
			(stroke
				(width 0.1)
				(type default)
			)
			(layer "F.Fab")
		)
		(fp_line
			(start -0.12065 -0.305054)
			(end -0.12065 -0.2794)
			(stroke
				(width 0.1)
				(type default)
			)
			(layer "F.Fab")
		)
		(fp_line
			(start -0.67945 0.3048)
			(end -0.67945 -0.305054)
			(stroke
				(width 0.1)
				(type default)
			)
			(layer "F.Fab")
		)
		(fp_line
			(start -0.67945 -0.305054)
			(end -0.12065 -0.305054)
			(stroke
				(width 0.1)
				(type default)
			)
			(layer "F.Fab")
		)
		(pad "1" smd circle
			(at -0.40005 0 180)
			(size 0 0)
			(layers "F.Cu" "F.Mask" "F.Paste")
			(net "GND")
		)
		(pad "2" smd circle
			(at 0.40005 0 180)
			(size 0 0)
			(layers "F.Cu" "F.Mask" "F.Paste")
			(net "P3V3_AUX")
		)
	)
	(footprint ""
		(layer "F.Cu")
		(at 134.513828 -343.952322 90)
		(property "Reference" "C2270"
			(at 0 0 90)
			(layer "F.SilkS")
			(hide yes)
			(effects
				(font
					(size 1.27 1.27)
				)
			)
		)
		(property "Value" ""
			(at 0 0 90)
			(layer "F.Fab")
			(effects
				(font
					(size 1.27 1.27)
				)
			)
		)
		(duplicate_pad_numbers_are_jumpers no)
		(fp_line
			(start 0.299974 -0.150114)
			(end 0.299974 0.150114)
			(stroke
				(width 0.1)
				(type default)
			)
			(layer "F.Fab")
		)
		(fp_line
			(start -0.299974 -0.150114)
			(end 0.299974 -0.150114)
			(stroke
				(width 0.1)
				(type default)
			)
			(layer "F.Fab")
		)
		(fp_line
			(start 0.299974 0.150114)
			(end -0.299974 0.150114)
			(stroke
				(width 0.1)
				(type default)
			)
			(layer "F.Fab")
		)
		(fp_line
			(start -0.299974 0.150114)
			(end -0.299974 -0.150114)
			(stroke
				(width 0.1)
				(type default)
			)
			(layer "F.Fab")
		)
		(pad "1" smd rect
			(at -0.2667 0 90)
			(size 0.3048 0.381)
			(layers "F.Cu" "F.Mask" "F.Paste")
			(net "P5E_PEX1_STN5_TX_DN<82>")
		)
		(pad "2" smd rect
			(at 0.2667 0 90)
			(size 0.3048 0.381)
			(layers "F.Cu" "F.Mask" "F.Paste")
			(net "P5E_PEX1_STN5_TX_C_DN<82>")
		)
	)
	(footprint ""
		(layer "F.Cu")
		(at 378.382022 -280.189432 180)
		(property "Reference" "C3595"
			(at 0 0 180)
			(layer "F.SilkS")
			(hide yes)
			(effects
				(font
					(size 1.27 1.27)
				)
			)
		)
		(property "Value" ""
			(at 0 0 180)
			(layer "F.Fab")
			(effects
				(font
					(size 1.27 1.27)
				)
			)
		)
		(duplicate_pad_numbers_are_jumpers no)
		(fp_line
			(start 1.2954 0.5842)
			(end -1.2954 0.5842)
			(stroke
				(width 0.1524)
				(type default)
			)
			(layer "F.SilkS")
		)
		(fp_line
			(start 1.2954 -0.5842)
			(end 1.2954 0.5842)
			(stroke
				(width 0.1524)
				(type default)
			)
			(layer "F.SilkS")
		)
		(fp_line
			(start -1.2954 0.5842)
			(end -1.2954 -0.5842)
			(stroke
				(width 0.1524)
				(type default)
			)
			(layer "F.SilkS")
		)
		(fp_line
			(start -1.2954 -0.5842)
			(end 1.2954 -0.5842)
			(stroke
				(width 0.1524)
				(type default)
			)
			(layer "F.SilkS")
		)
		(fp_line
			(start 1.1938 0.4064)
			(end 0.8636 0.4064)
			(stroke
				(width 0.1)
				(type default)
			)
			(layer "F.Fab")
		)
		(fp_line
			(start 1.1938 -0.4064)
			(end 1.1938 0.4064)
			(stroke
				(width 0.1)
				(type default)
			)
			(layer "F.Fab")
		)
		(fp_line
			(start 0.8636 0.4572)
			(end -0.8636 0.4572)
			(stroke
				(width 0.1)
				(type default)
			)
			(layer "F.Fab")
		)
		(fp_line
			(start 0.8636 0.4064)
			(end 0.8636 0.4572)
			(stroke
				(width 0.1)
				(type default)
			)
			(layer "F.Fab")
		)
		(fp_line
			(start 0.8636 -0.4064)
			(end 1.1938 -0.4064)
			(stroke
				(width 0.1)
				(type default)
			)
			(layer "F.Fab")
		)
		(fp_line
			(start 0.8636 -0.4572)
			(end 0.8636 -0.4064)
			(stroke
				(width 0.1)
				(type default)
			)
			(layer "F.Fab")
		)
		(fp_line
			(start -0.8636 0.4572)
			(end -0.8636 0.4064)
			(stroke
				(width 0.1)
				(type default)
			)
			(layer "F.Fab")
		)
		(fp_line
			(start -0.8636 0.4064)
			(end -1.1938 0.4064)
			(stroke
				(width 0.1)
				(type default)
			)
			(layer "F.Fab")
		)
		(fp_line
			(start -0.8636 -0.4064)
			(end -0.8636 -0.4572)
			(stroke
				(width 0.1)
				(type default)
			)
			(layer "F.Fab")
		)
		(fp_line
			(start -0.8636 -0.4572)
			(end 0.8636 -0.4572)
			(stroke
				(width 0.1)
				(type default)
			)
			(layer "F.Fab")
		)
		(fp_line
			(start -1.1938 0.4064)
			(end -1.1938 -0.4064)
			(stroke
				(width 0.1)
				(type default)
			)
			(layer "F.Fab")
		)
		(fp_line
			(start -1.1938 -0.4064)
			(end -0.8636 -0.4064)
			(stroke
				(width 0.1)
				(type default)
			)
			(layer "F.Fab")
		)
		(pad "1" smd rect
			(at -0.7366 0 90)
			(size 0.7112 0.8128)
			(layers "F.Cu" "F.Mask" "F.Paste")
			(net "SYSPLL_VDDA18_PEX3_R")
		)
		(pad "2" smd rect
			(at 0.7366 0 90)
			(size 0.7112 0.8128)
			(layers "F.Cu" "F.Mask" "F.Paste")
			(net "GND")
		)
	)
)
